# S9S_MB_2U (Grand Teton) — schematic netlist excerpt (pin names and nets, part order shuffled) for the footprints in the layout excerpt that follows; sources: Cadence DE-HDL packaged netlist, KiCad conversion of 03242023_DA0F0TMBIJ0_F0T_Motherboard_J_brd_V01_OCP.brd

R1443  Q_RES  33.2 1% CHIP  pkg 0402LF  page 222 : A = PWRGD_CPUPWRGD_LVC1 ; B = PWRGD_CPUPWRGD_LVC1_R
C2364  Q_CAP  0.1UF 25V 10% EMPTY  pkg 0402  page 251 : A = P3V3_AUX ; B = GND

(kicad_pcb
	(version 20260206)
	(generator "pcbnew")
	(generator_version "10.0")
	(general
		(thickness 1.6)
		(legacy_teardrops no)
	)
	(paper "A4")
	(title_block
		(title "03242023_DA0F0TMBIJ0_F0T_Motherboard_J_brd_V01_OCP.brd")
		(comment 1 "Grand Teton / footprints 2461-2462 of 6105")
	)
	(layers
		(0 "F.Cu" signal "TOP")
		(4 "In1.Cu" signal "GND")
		(6 "In2.Cu" signal "IN1")
		(8 "In3.Cu" signal "GND1")
		(10 "In4.Cu" signal "IN2")
		(12 "In5.Cu" signal "GND2")
		(14 "In6.Cu" signal "IN3")
		(16 "In7.Cu" signal "GND3")
		(18 "In8.Cu" signal "VCC")
		(20 "In9.Cu" signal "VCC1")
		(22 "In10.Cu" signal "GND4")
		(24 "In11.Cu" signal "IN4")
		(26 "In12.Cu" signal "GND5")
		(28 "In13.Cu" signal "IN5")
		(30 "In14.Cu" signal "GND6")
		(32 "In15.Cu" signal "IN6")
		(34 "In16.Cu" signal "GND7")
		(2 "B.Cu" signal "BOTTOM")
		(9 "F.Adhes" user "F.Adhesive")
		(11 "B.Adhes" user "B.Adhesive")
		(13 "F.Paste" user "Package Geometry/Pastemask Top")
		(15 "B.Paste" user "Package Geometry/Pastemask Bottom")
		(5 "F.SilkS" user "Ref Des/Silkscreen Top")
		(7 "B.SilkS" user "Ref Des/Silkscreen Bottom")
		(1 "F.Mask" user "Board Geometry/Soldermask Top")
		(3 "B.Mask" user "Board Geometry/Soldermask Bottom")
		(17 "Dwgs.User" user "User.Drawings")
		(19 "Cmts.User" user "User.Comments")
		(21 "Eco1.User" user "User.Eco1")
		(23 "Eco2.User" user "User.Eco2")
		(25 "Edge.Cuts" user "Board Geometry/Outline")
		(27 "Margin" user)
		(31 "F.CrtYd" user "Package Geometry/Place Bound Top")
		(29 "B.CrtYd" user "Package Geometry/Place Bound Bottom")
		(35 "F.Fab" user "Ref Des/Assembly Top")
		(33 "B.Fab" user "Ref Des/Assembly Bottom")
	)
	(footprint ""
		(layer "F.Cu")
		(at 301.01032 -411.604206 -90)
		(property "Reference" "C2364"
			(at 0 0 270)
			(layer "F.SilkS")
			(hide yes)
			(effects
				(font
					(size 1.27 1.27)
				)
			)
		)
		(property "Value" ""
			(at 0 0 270)
			(layer "F.Fab")
			(effects
				(font
					(size 1.27 1.27)
				)
			)
		)
		(duplicate_pad_numbers_are_jumpers no)
		(fp_line
			(start -0.7874 0.4064)
			(end -0.7874 -0.4064)
			(stroke
				(width 0.1524)
				(type default)
			)
			(layer "F.SilkS")
		)
		(fp_line
			(start 0.7874 0.4064)
			(end -0.7874 0.4064)
			(stroke
				(width 0.1524)
				(type default)
			)
			(layer "F.SilkS")
		)
		(fp_line
			(start -0.7874 -0.4064)
			(end 0.7874 -0.4064)
			(stroke
				(width 0.1524)
				(type default)
			)
			(layer "F.SilkS")
		)
		(fp_line
			(start 0.7874 -0.4064)
			(end 0.7874 0.4064)
			(stroke
				(width 0.1524)
				(type default)
			)
			(layer "F.SilkS")
		)
		(fp_line
			(start -0.67945 0.3048)
			(end -0.67945 -0.305054)
			(stroke
				(width 0.1)
				(type default)
			)
			(layer "F.Fab")
		)
		(fp_line
			(start -0.12065 0.3048)
			(end -0.67945 0.3048)
			(stroke
				(width 0.1)
				(type default)
			)
			(layer "F.Fab")
		)
		(fp_line
			(start 0.120396 0.3048)
			(end 0.120396 0.2794)
			(stroke
				(width 0.1)
				(type default)
			)
			(layer "F.Fab")
		)
		(fp_line
			(start 0.67945 0.3048)
			(end 0.120396 0.3048)
			(stroke
				(width 0.1)
				(type default)
			)
			(layer "F.Fab")
		)
		(fp_line
			(start -0.12065 0.2794)
			(end -0.12065 0.3048)
			(stroke
				(width 0.1)
				(type default)
			)
			(layer "F.Fab")
		)
		(fp_line
			(start 0.120396 0.2794)
			(end -0.12065 0.2794)
			(stroke
				(width 0.1)
				(type default)
			)
			(layer "F.Fab")
		)
		(fp_line
			(start -0.12065 -0.2794)
			(end 0.12065 -0.2794)
			(stroke
				(width 0.1)
				(type default)
			)
			(layer "F.Fab")
		)
		(fp_line
			(start 0.12065 -0.2794)
			(end 0.12065 -0.3048)
			(stroke
				(width 0.1)
				(type default)
			)
			(layer "F.Fab")
		)
		(fp_line
			(start 0.12065 -0.3048)
			(end 0.67945 -0.3048)
			(stroke
				(width 0.1)
				(type default)
			)
			(layer "F.Fab")
		)
		(fp_line
			(start 0.67945 -0.3048)
			(end 0.67945 0.3048)
			(stroke
				(width 0.1)
				(type default)
			)
			(layer "F.Fab")
		)
		(fp_line
			(start -0.67945 -0.305054)
			(end -0.12065 -0.305054)
			(stroke
				(width 0.1)
				(type default)
			)
			(layer "F.Fab")
		)
		(fp_line
			(start -0.12065 -0.305054)
			(end -0.12065 -0.2794)
			(stroke
				(width 0.1)
				(type default)
			)
			(layer "F.Fab")
		)
		(pad "1" smd circle
			(at -0.40005 0 270)
			(size 0 0)
			(layers "F.Cu" "F.Mask" "F.Paste")
			(net "P3V3_AUX")
		)
		(pad "2" smd circle
			(at 0.40005 0 270)
			(size 0 0)
			(layers "F.Cu" "F.Mask" "F.Paste")
			(net "GND")
		)
	)
	(footprint ""
		(layer "F.Cu")
		(at 113.21288 -101.793548 90)
		(property "Reference" "R1443"
			(at 0 0 90)
			(layer "F.SilkS")
			(hide yes)
			(effects
				(font
					(size 1.27 1.27)
				)
			)
		)
		(property "Value" ""
			(at 0 0 90)
			(layer "F.Fab")
			(effects
				(font
					(size 1.27 1.27)
				)
			)
		)
		(duplicate_pad_numbers_are_jumpers no)
		(fp_line
			(start 0.7874 -0.4064)
			(end 0.7874 0.4064)
			(stroke
				(width 0.1524)
				(type default)
			)
			(layer "F.SilkS")
		)
		(fp_line
			(start -0.7874 -0.4064)
			(end 0.7874 -0.4064)
			(stroke
				(width 0.1524)
				(type default)
			)
			(layer "F.SilkS")
		)
		(fp_line
			(start 0.7874 0.4064)
			(end -0.7874 0.4064)
			(stroke
				(width 0.1524)
				(type default)
			)
			(layer "F.SilkS")
		)
		(fp_line
			(start -0.7874 0.4064)
			(end -0.7874 -0.4064)
			(stroke
				(width 0.1524)
				(type default)
			)
			(layer "F.SilkS")
		)
		(fp_line
			(start -0.12065 -0.305054)
			(end -0.12065 -0.2794)
			(stroke
				(width 0.1)
				(type default)
			)
			(layer "F.Fab")
		)
		(fp_line
			(start -0.67945 -0.305054)
			(end -0.12065 -0.305054)
			(stroke
				(width 0.1)
				(type default)
			)
			(layer "F.Fab")
		)
		(fp_line
			(start 0.67945 -0.3048)
			(end 0.67945 0.3048)
			(stroke
				(width 0.1)
				(type default)
			)
			(layer "F.Fab")
		)
		(fp_line
			(start 0.12065 -0.3048)
			(end 0.67945 -0.3048)
			(stroke
				(width 0.1)
				(type default)
			)
			(layer "F.Fab")
		)
		(fp_line
			(start 0.12065 -0.2794)
			(end 0.12065 -0.3048)
			(stroke
				(width 0.1)
				(type default)
			)
			(layer "F.Fab")
		)
		(fp_line
			(start -0.12065 -0.2794)
			(end 0.12065 -0.2794)
			(stroke
				(width 0.1)
				(type default)
			)
			(layer "F.Fab")
		)
		(fp_line
			(start 0.120396 0.2794)
			(end -0.12065 0.2794)
			(stroke
				(width 0.1)
				(type default)
			)
			(layer "F.Fab")
		)
		(fp_line
			(start -0.12065 0.2794)
			(end -0.12065 0.3048)
			(stroke
				(width 0.1)
				(type default)
			)
			(layer "F.Fab")
		)
		(fp_line
			(start 0.67945 0.3048)
			(end 0.120396 0.3048)
			(stroke
				(width 0.1)
				(type default)
			)
			(layer "F.Fab")
		)
		(fp_line
			(start 0.120396 0.3048)
			(end 0.120396 0.2794)
			(stroke
				(width 0.1)
				(type default)
			)
			(layer "F.Fab")
		)
		(fp_line
			(start -0.12065 0.3048)
			(end -0.67945 0.3048)
			(stroke
				(width 0.1)
				(type default)
			)
			(layer "F.Fab")
		)
		(fp_line
			(start -0.67945 0.3048)
			(end -0.67945 -0.305054)
			(stroke
				(width 0.1)
				(type default)
			)
			(layer "F.Fab")
		)
		(pad "1" smd circle
			(at -0.40005 0 90)
			(size 0 0)
			(layers "F.Cu" "F.Mask" "F.Paste")
			(net "PWRGD_CPUPWRGD_LVC1")
		)
		(pad "2" smd circle
			(at 0.40005 0 90)
			(size 0 0)
			(layers "F.Cu" "F.Mask" "F.Paste")
			(net "PWRGD_CPUPWRGD_LVC1_R")
		)
	)
)
